(kicad_pcb
	(version 20260206)
	(generator "pcbnew")
	(generator_version "10.0")
	(general
		(thickness 1.6)
		(legacy_teardrops no)
	)
	(paper "A4")
	(title_block
		(title "Wiwynn_Tioga_Pass_MB.brd")
		(comment 1 "Tioga Pass / footprint 2031 of 4770 (J1A2), pads 244-291 of 291")
	)
	(layers
		(0 "F.Cu" signal "TOP")
		(4 "In1.Cu" signal "L2GND")
		(6 "In2.Cu" signal "L3")
		(8 "In3.Cu" signal "L4GND")
		(10 "In4.Cu" signal "L5")
		(12 "In5.Cu" signal "L6GND")
		(14 "In6.Cu" signal "L7VCC")
		(16 "In7.Cu" signal "L8VCC")
		(18 "In8.Cu" signal "L9GND")
		(20 "In9.Cu" signal "L10")
		(22 "In10.Cu" signal "L11GND")
		(24 "In11.Cu" signal "L12")
		(26 "In12.Cu" signal "L13GND")
		(2 "B.Cu" signal "BOTTOM")
		(9 "F.Adhes" user "F.Adhesive")
		(11 "B.Adhes" user "B.Adhesive")
		(13 "F.Paste" user "Package Geometry/Pastemask Top")
		(15 "B.Paste" user "Package Geometry/Pastemask Bottom")
		(5 "F.SilkS" user "Ref Des/Silkscreen Top")
		(7 "B.SilkS" user "Ref Des/Silkscreen Bottom")
		(1 "F.Mask" user "Board Geometry/Soldermask Top")
		(3 "B.Mask" user "Board Geometry/Soldermask Bottom")
		(17 "Dwgs.User" user "User.Drawings")
		(19 "Cmts.User" user "User.Comments")
		(21 "Eco1.User" user "User.Eco1")
		(23 "Eco2.User" user "User.Eco2")
		(25 "Edge.Cuts" user "Board Geometry/Outline")
		(27 "Margin" user)
		(31 "F.CrtYd" user "Package Geometry/Place Bound Top")
		(29 "B.CrtYd" user "Package Geometry/Place Bound Bottom")
		(35 "F.Fab" user "Ref Des/Assembly Top")
		(33 "B.Fab" user "Ref Des/Assembly Bottom")
	)
	(footprint ""
		(layer "F.Cu")
		(at 29.699458 -142.6718 90)
		(property "Reference" "J1A2"
			(at -2.623312 42.436542 0)
			(unlocked yes)
			(layer "F.SilkS")
			(effects
				(font
					(size 0.7874 0.5842)
					(thickness 0.1524)
				)
				(justify left)
			)
		)
		(property "Value" ""
			(at 0 0 90)
			(layer "F.Fab")
			(effects
				(font
					(size 1.27 1.27)
				)
			)
		)
		(duplicate_pad_numbers_are_jumpers no)
		(pad "241" smd rect
			(at 4.59994 86.700106 90)
			(size 1.8034 0.508)
			(layers "F.Cu" "F.Mask" "F.Paste")
			(net "GND")
		)
		(pad "242" smd rect
			(at 4.59994 87.54999 90)
			(size 1.8034 0.508)
			(layers "F.Cu" "F.Mask" "F.Paste")
			(net "M_L_DQ<32>")
		)
		(pad "243" smd rect
			(at 4.59994 88.399874 90)
			(size 1.8034 0.508)
			(layers "F.Cu" "F.Mask" "F.Paste")
			(net "GND")
		)
		(pad "244" smd rect
			(at 4.59994 89.250012 90)
			(size 1.8034 0.508)
			(layers "F.Cu" "F.Mask" "F.Paste")
			(net "M_L_DQS_DN<4>")
		)
		(pad "245" smd rect
			(at 4.59994 90.099896 90)
			(size 1.8034 0.508)
			(layers "F.Cu" "F.Mask" "F.Paste")
			(net "M_L_DQS_DP<4>")
		)
		(pad "246" smd rect
			(at 4.59994 90.950034 90)
			(size 1.8034 0.508)
			(layers "F.Cu" "F.Mask" "F.Paste")
			(net "GND")
		)
		(pad "247" smd rect
			(at 4.59994 91.799918 90)
			(size 1.8034 0.508)
			(layers "F.Cu" "F.Mask" "F.Paste")
			(net "M_L_DQ<38>")
		)
		(pad "248" smd rect
			(at 4.59994 92.650056 90)
			(size 1.8034 0.508)
			(layers "F.Cu" "F.Mask" "F.Paste")
			(net "GND")
		)
		(pad "249" smd rect
			(at 4.59994 93.49994 90)
			(size 1.8034 0.508)
			(layers "F.Cu" "F.Mask" "F.Paste")
			(net "M_L_DQ<34>")
		)
		(pad "250" smd rect
			(at 4.59994 94.350078 90)
			(size 1.8034 0.508)
			(layers "F.Cu" "F.Mask" "F.Paste")
			(net "GND")
		)
		(pad "251" smd rect
			(at 4.59994 95.199962 90)
			(size 1.8034 0.508)
			(layers "F.Cu" "F.Mask" "F.Paste")
			(net "M_L_DQ<44>")
		)
		(pad "252" smd rect
			(at 4.59994 96.0501 90)
			(size 1.8034 0.508)
			(layers "F.Cu" "F.Mask" "F.Paste")
			(net "GND")
		)
		(pad "253" smd rect
			(at 4.59994 96.899984 90)
			(size 1.8034 0.508)
			(layers "F.Cu" "F.Mask" "F.Paste")
			(net "M_L_DQ<40>")
		)
		(pad "254" smd rect
			(at 4.59994 97.750122 90)
			(size 1.8034 0.508)
			(layers "F.Cu" "F.Mask" "F.Paste")
			(net "GND")
		)
		(pad "255" smd rect
			(at 4.59994 98.600006 90)
			(size 1.8034 0.508)
			(layers "F.Cu" "F.Mask" "F.Paste")
			(net "M_L_DQS_DN<5>")
		)
		(pad "256" smd rect
			(at 4.59994 99.44989 90)
			(size 1.8034 0.508)
			(layers "F.Cu" "F.Mask" "F.Paste")
			(net "M_L_DQS_DP<5>")
		)
		(pad "257" smd rect
			(at 4.59994 100.300028 90)
			(size 1.8034 0.508)
			(layers "F.Cu" "F.Mask" "F.Paste")
			(net "GND")
		)
		(pad "258" smd rect
			(at 4.59994 101.149912 90)
			(size 1.8034 0.508)
			(layers "F.Cu" "F.Mask" "F.Paste")
			(net "M_L_DQ<46>")
		)
		(pad "259" smd rect
			(at 4.59994 102.00005 90)
			(size 1.8034 0.508)
			(layers "F.Cu" "F.Mask" "F.Paste")
			(net "GND")
		)
		(pad "260" smd rect
			(at 4.59994 102.849934 90)
			(size 1.8034 0.508)
			(layers "F.Cu" "F.Mask" "F.Paste")
			(net "M_L_DQ<42>")
		)
		(pad "261" smd rect
			(at 4.59994 103.700072 90)
			(size 1.8034 0.508)
			(layers "F.Cu" "F.Mask" "F.Paste")
			(net "GND")
		)
		(pad "262" smd rect
			(at 4.59994 104.549956 90)
			(size 1.8034 0.508)
			(layers "F.Cu" "F.Mask" "F.Paste")
			(net "M_L_DQ<52>")
		)
		(pad "263" smd rect
			(at 4.59994 105.400094 90)
			(size 1.8034 0.508)
			(layers "F.Cu" "F.Mask" "F.Paste")
			(net "GND")
		)
		(pad "264" smd rect
			(at 4.59994 106.249978 90)
			(size 1.8034 0.508)
			(layers "F.Cu" "F.Mask" "F.Paste")
			(net "M_L_DQ<48>")
		)
		(pad "265" smd rect
			(at 4.59994 107.100116 90)
			(size 1.8034 0.508)
			(layers "F.Cu" "F.Mask" "F.Paste")
			(net "GND")
		)
		(pad "266" smd rect
			(at 4.59994 107.95 90)
			(size 1.8034 0.508)
			(layers "F.Cu" "F.Mask" "F.Paste")
			(net "M_L_DQS_DN<6>")
		)
		(pad "267" smd rect
			(at 4.59994 108.799884 90)
			(size 1.8034 0.508)
			(layers "F.Cu" "F.Mask" "F.Paste")
			(net "M_L_DQS_DP<6>")
		)
		(pad "268" smd rect
			(at 4.59994 109.650022 90)
			(size 1.8034 0.508)
			(layers "F.Cu" "F.Mask" "F.Paste")
			(net "GND")
		)
		(pad "269" smd rect
			(at 4.59994 110.499906 90)
			(size 1.8034 0.508)
			(layers "F.Cu" "F.Mask" "F.Paste")
			(net "M_L_DQ<54>")
		)
		(pad "270" smd rect
			(at 4.59994 111.350044 90)
			(size 1.8034 0.508)
			(layers "F.Cu" "F.Mask" "F.Paste")
			(net "GND")
		)
		(pad "271" smd rect
			(at 4.59994 112.199928 90)
			(size 1.8034 0.508)
			(layers "F.Cu" "F.Mask" "F.Paste")
			(net "M_L_DQ<50>")
		)
		(pad "272" smd rect
			(at 4.59994 113.050066 90)
			(size 1.8034 0.508)
			(layers "F.Cu" "F.Mask" "F.Paste")
			(net "GND")
		)
		(pad "273" smd rect
			(at 4.59994 113.89995 90)
			(size 1.8034 0.508)
			(layers "F.Cu" "F.Mask" "F.Paste")
			(net "M_L_DQ<60>")
		)
		(pad "274" smd rect
			(at 4.59994 114.750088 90)
			(size 1.8034 0.508)
			(layers "F.Cu" "F.Mask" "F.Paste")
			(net "GND")
		)
		(pad "275" smd rect
			(at 4.59994 115.599972 90)
			(size 1.8034 0.508)
			(layers "F.Cu" "F.Mask" "F.Paste")
			(net "M_L_DQ<56>")
		)
		(pad "276" smd rect
			(at 4.59994 116.45011 90)
			(size 1.8034 0.508)
			(layers "F.Cu" "F.Mask" "F.Paste")
			(net "GND")
		)
		(pad "277" smd rect
			(at 4.59994 117.299994 90)
			(size 1.8034 0.508)
			(layers "F.Cu" "F.Mask" "F.Paste")
			(net "M_L_DQS_DN<7>")
		)
		(pad "278" smd rect
			(at 4.59994 118.149878 90)
			(size 1.8034 0.508)
			(layers "F.Cu" "F.Mask" "F.Paste")
			(net "M_L_DQS_DP<7>")
		)
		(pad "279" smd rect
			(at 4.59994 119.000016 90)
			(size 1.8034 0.508)
			(layers "F.Cu" "F.Mask" "F.Paste")
			(net "GND")
		)
		(pad "280" smd rect
			(at 4.59994 119.8499 90)
			(size 1.8034 0.508)
			(layers "F.Cu" "F.Mask" "F.Paste")
			(net "M_L_DQ<62>")
		)
		(pad "281" smd rect
			(at 4.59994 120.700038 90)
			(size 1.8034 0.508)
			(layers "F.Cu" "F.Mask" "F.Paste")
			(net "GND")
		)
		(pad "282" smd rect
			(at 4.59994 121.549922 90)
			(size 1.8034 0.508)
			(layers "F.Cu" "F.Mask" "F.Paste")
			(net "M_L_DQ<58>")
		)
		(pad "283" smd rect
			(at 4.59994 122.40006 90)
			(size 1.8034 0.508)
			(layers "F.Cu" "F.Mask" "F.Paste")
			(net "GND")
		)
		(pad "284" smd rect
			(at 4.59994 123.249944 90)
			(size 1.8034 0.508)
			(layers "F.Cu" "F.Mask" "F.Paste")
			(net "PVPP_KLM")
		)
		(pad "285" smd rect
			(at 4.59994 124.100082 90)
			(size 1.8034 0.508)
			(layers "F.Cu" "F.Mask" "F.Paste")
			(net "SMB_DDR_KLM_VPP_SDA")
		)
		(pad "286" smd rect
			(at 4.59994 124.949966 90)
			(size 1.8034 0.508)
			(layers "F.Cu" "F.Mask" "F.Paste")
			(net "PVPP_KLM")
		)
		(pad "287" smd rect
			(at 4.59994 125.800104 90)
			(size 1.8034 0.508)
			(layers "F.Cu" "F.Mask" "F.Paste")
			(net "PVPP_KLM")
		)
		(pad "288" smd rect
			(at 4.59994 126.649988 90)
			(size 1.8034 0.508)
			(layers "F.Cu" "F.Mask" "F.Paste")
			(net "PVPP_KLM")
		)
	)
)
